(kicad_pcb
	(version 20260206)
	(generator "pcbnew")
	(generator_version "10.0")
	(general
		(thickness 1.6)
		(legacy_teardrops no)
	)
	(paper "A4")
	(title_block
		(title "04192023_DAF0TMB3IC0_F0TG_MB_C_brd_V02_OCP.brd")
		(comment 1 "Grand Teton / footprints 3307-3313 of 8354")
	)
	(layers
		(0 "F.Cu" signal "TOP")
		(4 "In1.Cu" signal "GND")
		(6 "In2.Cu" signal "IN1")
		(8 "In3.Cu" signal "GND1")
		(10 "In4.Cu" signal "IN2")
		(12 "In5.Cu" signal "GND2")
		(14 "In6.Cu" signal "IN3")
		(16 "In7.Cu" signal "GND3")
		(18 "In8.Cu" signal "VCC")
		(20 "In9.Cu" signal "VCC1")
		(22 "In10.Cu" signal "GND4")
		(24 "In11.Cu" signal "IN4")
		(26 "In12.Cu" signal "GND5")
		(28 "In13.Cu" signal "IN5")
		(30 "In14.Cu" signal "GND6")
		(32 "In15.Cu" signal "IN6")
		(34 "In16.Cu" signal "GND7")
		(2 "B.Cu" signal "BOTTOM")
		(9 "F.Adhes" user "F.Adhesive")
		(11 "B.Adhes" user "B.Adhesive")
		(13 "F.Paste" user "Package Geometry/Pastemask Top")
		(15 "B.Paste" user "Package Geometry/Pastemask Bottom")
		(5 "F.SilkS" user "Ref Des/Silkscreen Top")
		(7 "B.SilkS" user "Ref Des/Silkscreen Bottom")
		(1 "F.Mask" user "Board Geometry/Soldermask Top")
		(3 "B.Mask" user "Board Geometry/Soldermask Bottom")
		(17 "Dwgs.User" user "User.Drawings")
		(19 "Cmts.User" user "User.Comments")
		(21 "Eco1.User" user "User.Eco1")
		(23 "Eco2.User" user "User.Eco2")
		(25 "Edge.Cuts" user "Board Geometry/Outline")
		(27 "Margin" user)
		(31 "F.CrtYd" user "Package Geometry/Place Bound Top")
		(29 "B.CrtYd" user "Package Geometry/Place Bound Bottom")
		(35 "F.Fab" user "Ref Des/Assembly Top")
		(33 "B.Fab" user "Ref Des/Assembly Bottom")
	)
	(footprint ""
		(layer "F.Cu")
		(at 323.062346 -416.899344 -90)
		(property "Reference" "C6513"
			(at 0 0 270)
			(layer "F.SilkS")
			(hide yes)
			(effects
				(font
					(size 1.27 1.27)
				)
			)
		)
		(property "Value" ""
			(at 0 0 270)
			(layer "F.Fab")
			(effects
				(font
					(size 1.27 1.27)
				)
			)
		)
		(duplicate_pad_numbers_are_jumpers no)
		(fp_line
			(start -0.299974 0.150114)
			(end -0.299974 -0.150114)
			(stroke
				(width 0.1)
				(type default)
			)
			(layer "F.Fab")
		)
		(fp_line
			(start 0.299974 0.150114)
			(end -0.299974 0.150114)
			(stroke
				(width 0.1)
				(type default)
			)
			(layer "F.Fab")
		)
		(fp_line
			(start -0.299974 -0.150114)
			(end 0.299974 -0.150114)
			(stroke
				(width 0.1)
				(type default)
			)
			(layer "F.Fab")
		)
		(fp_line
			(start 0.299974 -0.150114)
			(end 0.299974 0.150114)
			(stroke
				(width 0.1)
				(type default)
			)
			(layer "F.Fab")
		)
		(pad "1" smd rect
			(at -0.2667 0 270)
			(size 0.3048 0.381)
			(layers "F.Cu" "F.Mask" "F.Paste")
			(net "P5E_CPU0_P0_TX_BUF_C_DP<6>")
		)
		(pad "2" smd rect
			(at 0.2667 0 270)
			(size 0.3048 0.381)
			(layers "F.Cu" "F.Mask" "F.Paste")
			(net "P5E_CPU0_P0_TX_BUF_DP<6>")
		)
	)
	(footprint ""
		(layer "F.Cu")
		(at 109.549946 -52.86248 -90)
		(property "Reference" "R6307"
			(at 0 0 270)
			(layer "F.SilkS")
			(hide yes)
			(effects
				(font
					(size 1.27 1.27)
				)
			)
		)
		(property "Value" ""
			(at 0 0 270)
			(layer "F.Fab")
			(effects
				(font
					(size 1.27 1.27)
				)
			)
		)
		(duplicate_pad_numbers_are_jumpers no)
		(fp_line
			(start -0.7874 0.4064)
			(end -0.7874 -0.4064)
			(stroke
				(width 0.1524)
				(type default)
			)
			(layer "F.SilkS")
		)
		(fp_line
			(start 0.7874 0.4064)
			(end -0.7874 0.4064)
			(stroke
				(width 0.1524)
				(type default)
			)
			(layer "F.SilkS")
		)
		(fp_line
			(start -0.7874 -0.4064)
			(end 0.7874 -0.4064)
			(stroke
				(width 0.1524)
				(type default)
			)
			(layer "F.SilkS")
		)
		(fp_line
			(start 0.7874 -0.4064)
			(end 0.7874 0.4064)
			(stroke
				(width 0.1524)
				(type default)
			)
			(layer "F.SilkS")
		)
		(fp_line
			(start -0.67945 0.3048)
			(end -0.67945 -0.305054)
			(stroke
				(width 0.1)
				(type default)
			)
			(layer "F.Fab")
		)
		(fp_line
			(start -0.12065 0.3048)
			(end -0.67945 0.3048)
			(stroke
				(width 0.1)
				(type default)
			)
			(layer "F.Fab")
		)
		(fp_line
			(start 0.120396 0.3048)
			(end 0.120396 0.2794)
			(stroke
				(width 0.1)
				(type default)
			)
			(layer "F.Fab")
		)
		(fp_line
			(start 0.67945 0.3048)
			(end 0.120396 0.3048)
			(stroke
				(width 0.1)
				(type default)
			)
			(layer "F.Fab")
		)
		(fp_line
			(start -0.12065 0.2794)
			(end -0.12065 0.3048)
			(stroke
				(width 0.1)
				(type default)
			)
			(layer "F.Fab")
		)
		(fp_line
			(start 0.120396 0.2794)
			(end -0.12065 0.2794)
			(stroke
				(width 0.1)
				(type default)
			)
			(layer "F.Fab")
		)
		(fp_line
			(start -0.12065 -0.2794)
			(end 0.12065 -0.2794)
			(stroke
				(width 0.1)
				(type default)
			)
			(layer "F.Fab")
		)
		(fp_line
			(start 0.12065 -0.2794)
			(end 0.12065 -0.3048)
			(stroke
				(width 0.1)
				(type default)
			)
			(layer "F.Fab")
		)
		(fp_line
			(start 0.12065 -0.3048)
			(end 0.67945 -0.3048)
			(stroke
				(width 0.1)
				(type default)
			)
			(layer "F.Fab")
		)
		(fp_line
			(start 0.67945 -0.3048)
			(end 0.67945 0.3048)
			(stroke
				(width 0.1)
				(type default)
			)
			(layer "F.Fab")
		)
		(fp_line
			(start -0.67945 -0.305054)
			(end -0.12065 -0.305054)
			(stroke
				(width 0.1)
				(type default)
			)
			(layer "F.Fab")
		)
		(fp_line
			(start -0.12065 -0.305054)
			(end -0.12065 -0.2794)
			(stroke
				(width 0.1)
				(type default)
			)
			(layer "F.Fab")
		)
		(pad "1" smd circle
			(at -0.40005 0 270)
			(size 0 0)
			(layers "F.Cu" "F.Mask" "F.Paste")
			(net "USB_HUB2_TI_HS_SUSPEND")
		)
		(pad "2" smd circle
			(at 0.40005 0 270)
			(size 0 0)
			(layers "F.Cu" "F.Mask" "F.Paste")
			(net "GND")
		)
	)
	(footprint ""
		(layer "F.Cu")
		(at 323.100446 -99.284536)
		(property "Reference" "R1275"
			(at 0 0 0)
			(layer "F.SilkS")
			(hide yes)
			(effects
				(font
					(size 1.27 1.27)
				)
			)
		)
		(property "Value" ""
			(at 0 0 0)
			(layer "F.Fab")
			(effects
				(font
					(size 1.27 1.27)
				)
			)
		)
		(duplicate_pad_numbers_are_jumpers no)
		(fp_line
			(start -0.7874 -0.4064)
			(end 0.7874 -0.4064)
			(stroke
				(width 0.1524)
				(type default)
			)
			(layer "F.SilkS")
		)
		(fp_line
			(start -0.7874 0.4064)
			(end -0.7874 -0.4064)
			(stroke
				(width 0.1524)
				(type default)
			)
			(layer "F.SilkS")
		)
		(fp_line
			(start 0.7874 -0.4064)
			(end 0.7874 0.4064)
			(stroke
				(width 0.1524)
				(type default)
			)
			(layer "F.SilkS")
		)
		(fp_line
			(start 0.7874 0.4064)
			(end -0.7874 0.4064)
			(stroke
				(width 0.1524)
				(type default)
			)
			(layer "F.SilkS")
		)
		(fp_line
			(start -0.67945 -0.305054)
			(end -0.12065 -0.305054)
			(stroke
				(width 0.1)
				(type default)
			)
			(layer "F.Fab")
		)
		(fp_line
			(start -0.67945 0.3048)
			(end -0.67945 -0.305054)
			(stroke
				(width 0.1)
				(type default)
			)
			(layer "F.Fab")
		)
		(fp_line
			(start -0.12065 -0.305054)
			(end -0.12065 -0.2794)
			(stroke
				(width 0.1)
				(type default)
			)
			(layer "F.Fab")
		)
		(fp_line
			(start -0.12065 -0.2794)
			(end 0.12065 -0.2794)
			(stroke
				(width 0.1)
				(type default)
			)
			(layer "F.Fab")
		)
		(fp_line
			(start -0.12065 0.2794)
			(end -0.12065 0.3048)
			(stroke
				(width 0.1)
				(type default)
			)
			(layer "F.Fab")
		)
		(fp_line
			(start -0.12065 0.3048)
			(end -0.67945 0.3048)
			(stroke
				(width 0.1)
				(type default)
			)
			(layer "F.Fab")
		)
		(fp_line
			(start 0.120396 0.2794)
			(end -0.12065 0.2794)
			(stroke
				(width 0.1)
				(type default)
			)
			(layer "F.Fab")
		)
		(fp_line
			(start 0.120396 0.3048)
			(end 0.120396 0.2794)
			(stroke
				(width 0.1)
				(type default)
			)
			(layer "F.Fab")
		)
		(fp_line
			(start 0.12065 -0.3048)
			(end 0.67945 -0.3048)
			(stroke
				(width 0.1)
				(type default)
			)
			(layer "F.Fab")
		)
		(fp_line
			(start 0.12065 -0.2794)
			(end 0.12065 -0.3048)
			(stroke
				(width 0.1)
				(type default)
			)
			(layer "F.Fab")
		)
		(fp_line
			(start 0.67945 -0.3048)
			(end 0.67945 0.3048)
			(stroke
				(width 0.1)
				(type default)
			)
			(layer "F.Fab")
		)
		(fp_line
			(start 0.67945 0.3048)
			(end 0.120396 0.3048)
			(stroke
				(width 0.1)
				(type default)
			)
			(layer "F.Fab")
		)
		(pad "1" smd circle
			(at -0.40005 0)
			(size 0 0)
			(layers "F.Cu" "F.Mask" "F.Paste")
			(net "SMB_INA230_8_3V3AUX_SDA_R")
		)
		(pad "2" smd circle
			(at 0.40005 0)
			(size 0 0)
			(layers "F.Cu" "F.Mask" "F.Paste")
			(net "SMB_INA230_8_3V3AUX_SDA_R1")
		)
	)
	(footprint ""
		(layer "F.Cu")
		(at 197.269608 -120.991376)
		(property "Reference" "R4147"
			(at 0 0 0)
			(layer "F.SilkS")
			(hide yes)
			(effects
				(font
					(size 1.27 1.27)
				)
			)
		)
		(property "Value" ""
			(at 0 0 0)
			(layer "F.Fab")
			(effects
				(font
					(size 1.27 1.27)
				)
			)
		)
		(duplicate_pad_numbers_are_jumpers no)
		(fp_line
			(start -0.7874 -0.4064)
			(end 0.7874 -0.4064)
			(stroke
				(width 0.1524)
				(type default)
			)
			(layer "F.SilkS")
		)
		(fp_line
			(start -0.7874 0.4064)
			(end -0.7874 -0.4064)
			(stroke
				(width 0.1524)
				(type default)
			)
			(layer "F.SilkS")
		)
		(fp_line
			(start 0.7874 -0.4064)
			(end 0.7874 0.4064)
			(stroke
				(width 0.1524)
				(type default)
			)
			(layer "F.SilkS")
		)
		(fp_line
			(start 0.7874 0.4064)
			(end -0.7874 0.4064)
			(stroke
				(width 0.1524)
				(type default)
			)
			(layer "F.SilkS")
		)
		(fp_line
			(start -0.67945 -0.305054)
			(end -0.12065 -0.305054)
			(stroke
				(width 0.1)
				(type default)
			)
			(layer "F.Fab")
		)
		(fp_line
			(start -0.67945 0.3048)
			(end -0.67945 -0.305054)
			(stroke
				(width 0.1)
				(type default)
			)
			(layer "F.Fab")
		)
		(fp_line
			(start -0.12065 -0.305054)
			(end -0.12065 -0.2794)
			(stroke
				(width 0.1)
				(type default)
			)
			(layer "F.Fab")
		)
		(fp_line
			(start -0.12065 -0.2794)
			(end 0.12065 -0.2794)
			(stroke
				(width 0.1)
				(type default)
			)
			(layer "F.Fab")
		)
		(fp_line
			(start -0.12065 0.2794)
			(end -0.12065 0.3048)
			(stroke
				(width 0.1)
				(type default)
			)
			(layer "F.Fab")
		)
		(fp_line
			(start -0.12065 0.3048)
			(end -0.67945 0.3048)
			(stroke
				(width 0.1)
				(type default)
			)
			(layer "F.Fab")
		)
		(fp_line
			(start 0.120396 0.2794)
			(end -0.12065 0.2794)
			(stroke
				(width 0.1)
				(type default)
			)
			(layer "F.Fab")
		)
		(fp_line
			(start 0.120396 0.3048)
			(end 0.120396 0.2794)
			(stroke
				(width 0.1)
				(type default)
			)
			(layer "F.Fab")
		)
		(fp_line
			(start 0.12065 -0.3048)
			(end 0.67945 -0.3048)
			(stroke
				(width 0.1)
				(type default)
			)
			(layer "F.Fab")
		)
		(fp_line
			(start 0.12065 -0.2794)
			(end 0.12065 -0.3048)
			(stroke
				(width 0.1)
				(type default)
			)
			(layer "F.Fab")
		)
		(fp_line
			(start 0.67945 -0.3048)
			(end 0.67945 0.3048)
			(stroke
				(width 0.1)
				(type default)
			)
			(layer "F.Fab")
		)
		(fp_line
			(start 0.67945 0.3048)
			(end 0.120396 0.3048)
			(stroke
				(width 0.1)
				(type default)
			)
			(layer "F.Fab")
		)
		(pad "1" smd circle
			(at -0.40005 0)
			(size 0 0)
			(layers "F.Cu" "F.Mask" "F.Paste")
			(net "PRSNT_CABLE_GPU_A2_ISO_R_N")
		)
		(pad "2" smd circle
			(at 0.40005 0)
			(size 0 0)
			(layers "F.Cu" "F.Mask" "F.Paste")
			(net "PRSNT_CABLE_GPU_A2_ISO_N")
		)
	)
	(footprint ""
		(layer "F.Cu")
		(at 108.627164 -261.748016 -90)
		(property "Reference" "C2500"
			(at 0 0 270)
			(layer "F.SilkS")
			(hide yes)
			(effects
				(font
					(size 1.27 1.27)
				)
			)
		)
		(property "Value" ""
			(at 0 0 270)
			(layer "F.Fab")
			(effects
				(font
					(size 1.27 1.27)
				)
			)
		)
		(duplicate_pad_numbers_are_jumpers no)
		(fp_line
			(start -0.7874 0.4064)
			(end -0.7874 -0.4064)
			(stroke
				(width 0.1524)
				(type default)
			)
			(layer "F.SilkS")
		)
		(fp_line
			(start 0.7874 0.4064)
			(end -0.7874 0.4064)
			(stroke
				(width 0.1524)
				(type default)
			)
			(layer "F.SilkS")
		)
		(fp_line
			(start -0.7874 -0.4064)
			(end 0.7874 -0.4064)
			(stroke
				(width 0.1524)
				(type default)
			)
			(layer "F.SilkS")
		)
		(fp_line
			(start 0.7874 -0.4064)
			(end 0.7874 0.4064)
			(stroke
				(width 0.1524)
				(type default)
			)
			(layer "F.SilkS")
		)
		(fp_line
			(start -0.67945 0.3048)
			(end -0.67945 -0.305054)
			(stroke
				(width 0.1)
				(type default)
			)
			(layer "F.Fab")
		)
		(fp_line
			(start -0.12065 0.3048)
			(end -0.67945 0.3048)
			(stroke
				(width 0.1)
				(type default)
			)
			(layer "F.Fab")
		)
		(fp_line
			(start 0.120396 0.3048)
			(end 0.120396 0.2794)
			(stroke
				(width 0.1)
				(type default)
			)
			(layer "F.Fab")
		)
		(fp_line
			(start 0.67945 0.3048)
			(end 0.120396 0.3048)
			(stroke
				(width 0.1)
				(type default)
			)
			(layer "F.Fab")
		)
		(fp_line
			(start -0.12065 0.2794)
			(end -0.12065 0.3048)
			(stroke
				(width 0.1)
				(type default)
			)
			(layer "F.Fab")
		)
		(fp_line
			(start 0.120396 0.2794)
			(end -0.12065 0.2794)
			(stroke
				(width 0.1)
				(type default)
			)
			(layer "F.Fab")
		)
		(fp_line
			(start -0.12065 -0.2794)
			(end 0.12065 -0.2794)
			(stroke
				(width 0.1)
				(type default)
			)
			(layer "F.Fab")
		)
		(fp_line
			(start 0.12065 -0.2794)
			(end 0.12065 -0.3048)
			(stroke
				(width 0.1)
				(type default)
			)
			(layer "F.Fab")
		)
		(fp_line
			(start 0.12065 -0.3048)
			(end 0.67945 -0.3048)
			(stroke
				(width 0.1)
				(type default)
			)
			(layer "F.Fab")
		)
		(fp_line
			(start 0.67945 -0.3048)
			(end 0.67945 0.3048)
			(stroke
				(width 0.1)
				(type default)
			)
			(layer "F.Fab")
		)
		(fp_line
			(start -0.67945 -0.305054)
			(end -0.12065 -0.305054)
			(stroke
				(width 0.1)
				(type default)
			)
			(layer "F.Fab")
		)
		(fp_line
			(start -0.12065 -0.305054)
			(end -0.12065 -0.2794)
			(stroke
				(width 0.1)
				(type default)
			)
			(layer "F.Fab")
		)
		(pad "1" smd circle
			(at -0.40005 0 270)
			(size 0 0)
			(layers "F.Cu" "F.Mask" "F.Paste")
			(net "PVDD11_S3_P1")
		)
		(pad "2" smd circle
			(at 0.40005 0 270)
			(size 0 0)
			(layers "F.Cu" "F.Mask" "F.Paste")
			(net "GND")
		)
	)
	(footprint ""
		(layer "F.Cu")
		(at 304.419 -360.426 180)
		(property "Reference" "PC73"
			(at 0 0 180)
			(layer "F.SilkS")
			(hide yes)
			(effects
				(font
					(size 1.27 1.27)
				)
			)
		)
		(property "Value" ""
			(at 0 0 180)
			(layer "F.Fab")
			(effects
				(font
					(size 1.27 1.27)
				)
			)
		)
		(duplicate_pad_numbers_are_jumpers no)
		(fp_line
			(start 0.7874 0.4064)
			(end -0.7874 0.4064)
			(stroke
				(width 0.1524)
				(type default)
			)
			(layer "F.SilkS")
		)
		(fp_line
			(start 0.7874 -0.4064)
			(end 0.7874 0.4064)
			(stroke
				(width 0.1524)
				(type default)
			)
			(layer "F.SilkS")
		)
		(fp_line
			(start -0.7874 0.4064)
			(end -0.7874 -0.4064)
			(stroke
				(width 0.1524)
				(type default)
			)
			(layer "F.SilkS")
		)
		(fp_line
			(start -0.7874 -0.4064)
			(end 0.7874 -0.4064)
			(stroke
				(width 0.1524)
				(type default)
			)
			(layer "F.SilkS")
		)
		(fp_line
			(start 0.67945 0.3048)
			(end 0.120396 0.3048)
			(stroke
				(width 0.1)
				(type default)
			)
			(layer "F.Fab")
		)
		(fp_line
			(start 0.67945 -0.3048)
			(end 0.67945 0.3048)
			(stroke
				(width 0.1)
				(type default)
			)
			(layer "F.Fab")
		)
		(fp_line
			(start 0.12065 -0.2794)
			(end 0.12065 -0.3048)
			(stroke
				(width 0.1)
				(type default)
			)
			(layer "F.Fab")
		)
		(fp_line
			(start 0.12065 -0.3048)
			(end 0.67945 -0.3048)
			(stroke
				(width 0.1)
				(type default)
			)
			(layer "F.Fab")
		)
		(fp_line
			(start 0.120396 0.3048)
			(end 0.120396 0.2794)
			(stroke
				(width 0.1)
				(type default)
			)
			(layer "F.Fab")
		)
		(fp_line
			(start 0.120396 0.2794)
			(end -0.12065 0.2794)
			(stroke
				(width 0.1)
				(type default)
			)
			(layer "F.Fab")
		)
		(fp_line
			(start -0.12065 0.3048)
			(end -0.67945 0.3048)
			(stroke
				(width 0.1)
				(type default)
			)
			(layer "F.Fab")
		)
		(fp_line
			(start -0.12065 0.2794)
			(end -0.12065 0.3048)
			(stroke
				(width 0.1)
				(type default)
			)
			(layer "F.Fab")
		)
		(fp_line
			(start -0.12065 -0.2794)
			(end 0.12065 -0.2794)
			(stroke
				(width 0.1)
				(type default)
			)
			(layer "F.Fab")
		)
		(fp_line
			(start -0.12065 -0.305054)
			(end -0.12065 -0.2794)
			(stroke
				(width 0.1)
				(type default)
			)
			(layer "F.Fab")
		)
		(fp_line
			(start -0.67945 0.3048)
			(end -0.67945 -0.305054)
			(stroke
				(width 0.1)
				(type default)
			)
			(layer "F.Fab")
		)
		(fp_line
			(start -0.67945 -0.305054)
			(end -0.12065 -0.305054)
			(stroke
				(width 0.1)
				(type default)
			)
			(layer "F.Fab")
		)
		(pad "1" smd circle
			(at -0.40005 0 180)
			(size 0 0)
			(layers "F.Cu" "F.Mask" "F.Paste")
			(net "PVDD18_S5_P0")
		)
		(pad "2" smd circle
			(at 0.40005 0 180)
			(size 0 0)
			(layers "F.Cu" "F.Mask" "F.Paste")
			(net "GND")
		)
	)
	(footprint ""
		(layer "F.Cu")
		(at 102.75697 -180.027834 -90)
		(property "Reference" "PC286"
			(at 0 0 270)
			(layer "F.SilkS")
			(hide yes)
			(effects
				(font
					(size 1.27 1.27)
				)
			)
		)
		(property "Value" ""
			(at 0 0 270)
			(layer "F.Fab")
			(effects
				(font
					(size 1.27 1.27)
				)
			)
		)
		(duplicate_pad_numbers_are_jumpers no)
		(fp_line
			(start -0.7874 0.4064)
			(end -0.7874 -0.4064)
			(stroke
				(width 0.1524)
				(type default)
			)
			(layer "F.SilkS")
		)
		(fp_line
			(start -0.235966 0.4064)
			(end -0.7874 0.4064)
			(stroke
				(width 0.1524)
				(type default)
			)
			(layer "F.SilkS")
		)
		(fp_line
			(start 0.7874 0.4064)
			(end 0.373634 0.4064)
			(stroke
				(width 0.1524)
				(type default)
			)
			(layer "F.SilkS")
		)
		(fp_line
			(start -0.7874 -0.4064)
			(end 0.7874 -0.4064)
			(stroke
				(width 0.1524)
				(type default)
			)
			(layer "F.SilkS")
		)
		(fp_line
			(start 0.7874 -0.4064)
			(end 0.7874 0.4064)
			(stroke
				(width 0.1524)
				(type default)
			)
			(layer "F.SilkS")
		)
		(fp_line
			(start -0.67945 0.3048)
			(end -0.67945 -0.305054)
			(stroke
				(width 0.1)
				(type default)
			)
			(layer "F.Fab")
		)
		(fp_line
			(start -0.12065 0.3048)
			(end -0.67945 0.3048)
			(stroke
				(width 0.1)
				(type default)
			)
			(layer "F.Fab")
		)
		(fp_line
			(start 0.120396 0.3048)
			(end 0.120396 0.2794)
			(stroke
				(width 0.1)
				(type default)
			)
			(layer "F.Fab")
		)
		(fp_line
			(start 0.67945 0.3048)
			(end 0.120396 0.3048)
			(stroke
				(width 0.1)
				(type default)
			)
			(layer "F.Fab")
		)
		(fp_line
			(start -0.12065 0.2794)
			(end -0.12065 0.3048)
			(stroke
				(width 0.1)
				(type default)
			)
			(layer "F.Fab")
		)
		(fp_line
			(start 0.120396 0.2794)
			(end -0.12065 0.2794)
			(stroke
				(width 0.1)
				(type default)
			)
			(layer "F.Fab")
		)
		(fp_line
			(start -0.12065 -0.2794)
			(end 0.12065 -0.2794)
			(stroke
				(width 0.1)
				(type default)
			)
			(layer "F.Fab")
		)
		(fp_line
			(start 0.12065 -0.2794)
			(end 0.12065 -0.3048)
			(stroke
				(width 0.1)
				(type default)
			)
			(layer "F.Fab")
		)
		(fp_line
			(start 0.12065 -0.3048)
			(end 0.67945 -0.3048)
			(stroke
				(width 0.1)
				(type default)
			)
			(layer "F.Fab")
		)
		(fp_line
			(start 0.67945 -0.3048)
			(end 0.67945 0.3048)
			(stroke
				(width 0.1)
				(type default)
			)
			(layer "F.Fab")
		)
		(fp_line
			(start -0.67945 -0.305054)
			(end -0.12065 -0.305054)
			(stroke
				(width 0.1)
				(type default)
			)
			(layer "F.Fab")
		)
		(fp_line
			(start -0.12065 -0.305054)
			(end -0.12065 -0.2794)
			(stroke
				(width 0.1)
				(type default)
			)
			(layer "F.Fab")
		)
		(pad "1" smd circle
			(at -0.40005 0 270)
			(size 0 0)
			(layers "F.Cu" "F.Mask" "F.Paste")
			(net "PVDDCR_CPU0_P1_VCC3")
		)
		(pad "2" smd circle
			(at 0.40005 0 270)
			(size 0 0)
			(layers "F.Cu" "F.Mask" "F.Paste")
			(net "GND")
		)
	)
)
